(kicad_pcb
	(version 20260206)
	(generator "pcbnew")
	(generator_version "10.0")
	(general
		(thickness 1.6)
		(legacy_teardrops no)
	)
	(paper "A4")
	(title_block
		(title "04192023_DAF0TMB3IC0_F0TG_MB_C_brd_V02_OCP.brd")
		(comment 1 "Grand Teton / footprints 2024-2029 of 8354")
	)
	(layers
		(0 "F.Cu" signal "TOP")
		(4 "In1.Cu" signal "GND")
		(6 "In2.Cu" signal "IN1")
		(8 "In3.Cu" signal "GND1")
		(10 "In4.Cu" signal "IN2")
		(12 "In5.Cu" signal "GND2")
		(14 "In6.Cu" signal "IN3")
		(16 "In7.Cu" signal "GND3")
		(18 "In8.Cu" signal "VCC")
		(20 "In9.Cu" signal "VCC1")
		(22 "In10.Cu" signal "GND4")
		(24 "In11.Cu" signal "IN4")
		(26 "In12.Cu" signal "GND5")
		(28 "In13.Cu" signal "IN5")
		(30 "In14.Cu" signal "GND6")
		(32 "In15.Cu" signal "IN6")
		(34 "In16.Cu" signal "GND7")
		(2 "B.Cu" signal "BOTTOM")
		(9 "F.Adhes" user "F.Adhesive")
		(11 "B.Adhes" user "B.Adhesive")
		(13 "F.Paste" user "Package Geometry/Pastemask Top")
		(15 "B.Paste" user "Package Geometry/Pastemask Bottom")
		(5 "F.SilkS" user "Ref Des/Silkscreen Top")
		(7 "B.SilkS" user "Ref Des/Silkscreen Bottom")
		(1 "F.Mask" user "Board Geometry/Soldermask Top")
		(3 "B.Mask" user "Board Geometry/Soldermask Bottom")
		(17 "Dwgs.User" user "User.Drawings")
		(19 "Cmts.User" user "User.Comments")
		(21 "Eco1.User" user "User.Eco1")
		(23 "Eco2.User" user "User.Eco2")
		(25 "Edge.Cuts" user "Board Geometry/Outline")
		(27 "Margin" user)
		(31 "F.CrtYd" user "Package Geometry/Place Bound Top")
		(29 "B.CrtYd" user "Package Geometry/Place Bound Bottom")
		(35 "F.Fab" user "Ref Des/Assembly Top")
		(33 "B.Fab" user "Ref Des/Assembly Bottom")
	)
	(footprint ""
		(layer "F.Cu")
		(at 66.491612 -346.86875 -90)
		(property "Reference" "PC405_4"
			(at 0 0 270)
			(layer "F.SilkS")
			(hide yes)
			(effects
				(font
					(size 1.27 1.27)
				)
			)
		)
		(property "Value" ""
			(at 0 0 270)
			(layer "F.Fab")
			(effects
				(font
					(size 1.27 1.27)
				)
			)
		)
		(duplicate_pad_numbers_are_jumpers no)
		(fp_line
			(start -0.7874 0.4064)
			(end -0.7874 -0.4064)
			(stroke
				(width 0.1524)
				(type default)
			)
			(layer "F.SilkS")
		)
		(fp_line
			(start 0.7874 0.4064)
			(end -0.7874 0.4064)
			(stroke
				(width 0.1524)
				(type default)
			)
			(layer "F.SilkS")
		)
		(fp_line
			(start -0.7874 -0.4064)
			(end 0.7874 -0.4064)
			(stroke
				(width 0.1524)
				(type default)
			)
			(layer "F.SilkS")
		)
		(fp_line
			(start 0.7874 -0.4064)
			(end 0.7874 0.4064)
			(stroke
				(width 0.1524)
				(type default)
			)
			(layer "F.SilkS")
		)
		(fp_line
			(start -0.67945 0.3048)
			(end -0.67945 -0.305054)
			(stroke
				(width 0.1)
				(type default)
			)
			(layer "F.Fab")
		)
		(fp_line
			(start -0.12065 0.3048)
			(end -0.67945 0.3048)
			(stroke
				(width 0.1)
				(type default)
			)
			(layer "F.Fab")
		)
		(fp_line
			(start 0.120396 0.3048)
			(end 0.120396 0.2794)
			(stroke
				(width 0.1)
				(type default)
			)
			(layer "F.Fab")
		)
		(fp_line
			(start 0.67945 0.3048)
			(end 0.120396 0.3048)
			(stroke
				(width 0.1)
				(type default)
			)
			(layer "F.Fab")
		)
		(fp_line
			(start -0.12065 0.2794)
			(end -0.12065 0.3048)
			(stroke
				(width 0.1)
				(type default)
			)
			(layer "F.Fab")
		)
		(fp_line
			(start 0.120396 0.2794)
			(end -0.12065 0.2794)
			(stroke
				(width 0.1)
				(type default)
			)
			(layer "F.Fab")
		)
		(fp_line
			(start -0.12065 -0.2794)
			(end 0.12065 -0.2794)
			(stroke
				(width 0.1)
				(type default)
			)
			(layer "F.Fab")
		)
		(fp_line
			(start 0.12065 -0.2794)
			(end 0.12065 -0.3048)
			(stroke
				(width 0.1)
				(type default)
			)
			(layer "F.Fab")
		)
		(fp_line
			(start 0.12065 -0.3048)
			(end 0.67945 -0.3048)
			(stroke
				(width 0.1)
				(type default)
			)
			(layer "F.Fab")
		)
		(fp_line
			(start 0.67945 -0.3048)
			(end 0.67945 0.3048)
			(stroke
				(width 0.1)
				(type default)
			)
			(layer "F.Fab")
		)
		(fp_line
			(start -0.67945 -0.305054)
			(end -0.12065 -0.305054)
			(stroke
				(width 0.1)
				(type default)
			)
			(layer "F.Fab")
		)
		(fp_line
			(start -0.12065 -0.305054)
			(end -0.12065 -0.2794)
			(stroke
				(width 0.1)
				(type default)
			)
			(layer "F.Fab")
		)
		(pad "1" smd circle
			(at -0.40005 0 270)
			(size 0 0)
			(layers "F.Cu" "F.Mask" "F.Paste")
			(net "SW_P12V_AUX_PVDDCR_CPU1_P1_FLT")
		)
		(pad "2" smd circle
			(at 0.40005 0 270)
			(size 0 0)
			(layers "F.Cu" "F.Mask" "F.Paste")
			(net "GND")
		)
	)
	(footprint ""
		(layer "F.Cu")
		(at 132.610352 -52.28844 90)
		(property "Reference" "C1513"
			(at 0 0 90)
			(layer "F.SilkS")
			(hide yes)
			(effects
				(font
					(size 1.27 1.27)
				)
			)
		)
		(property "Value" ""
			(at 0 0 90)
			(layer "F.Fab")
			(effects
				(font
					(size 1.27 1.27)
				)
			)
		)
		(duplicate_pad_numbers_are_jumpers no)
		(fp_line
			(start 0.7874 -0.4064)
			(end 0.7874 0.4064)
			(stroke
				(width 0.1524)
				(type default)
			)
			(layer "F.SilkS")
		)
		(fp_line
			(start -0.7874 -0.4064)
			(end 0.7874 -0.4064)
			(stroke
				(width 0.1524)
				(type default)
			)
			(layer "F.SilkS")
		)
		(fp_line
			(start 0.7874 0.4064)
			(end -0.7874 0.4064)
			(stroke
				(width 0.1524)
				(type default)
			)
			(layer "F.SilkS")
		)
		(fp_line
			(start -0.7874 0.4064)
			(end -0.7874 -0.4064)
			(stroke
				(width 0.1524)
				(type default)
			)
			(layer "F.SilkS")
		)
		(fp_line
			(start -0.12065 -0.305054)
			(end -0.12065 -0.2794)
			(stroke
				(width 0.1)
				(type default)
			)
			(layer "F.Fab")
		)
		(fp_line
			(start -0.67945 -0.305054)
			(end -0.12065 -0.305054)
			(stroke
				(width 0.1)
				(type default)
			)
			(layer "F.Fab")
		)
		(fp_line
			(start 0.67945 -0.3048)
			(end 0.67945 0.3048)
			(stroke
				(width 0.1)
				(type default)
			)
			(layer "F.Fab")
		)
		(fp_line
			(start 0.12065 -0.3048)
			(end 0.67945 -0.3048)
			(stroke
				(width 0.1)
				(type default)
			)
			(layer "F.Fab")
		)
		(fp_line
			(start 0.12065 -0.2794)
			(end 0.12065 -0.3048)
			(stroke
				(width 0.1)
				(type default)
			)
			(layer "F.Fab")
		)
		(fp_line
			(start -0.12065 -0.2794)
			(end 0.12065 -0.2794)
			(stroke
				(width 0.1)
				(type default)
			)
			(layer "F.Fab")
		)
		(fp_line
			(start 0.120396 0.2794)
			(end -0.12065 0.2794)
			(stroke
				(width 0.1)
				(type default)
			)
			(layer "F.Fab")
		)
		(fp_line
			(start -0.12065 0.2794)
			(end -0.12065 0.3048)
			(stroke
				(width 0.1)
				(type default)
			)
			(layer "F.Fab")
		)
		(fp_line
			(start 0.67945 0.3048)
			(end 0.120396 0.3048)
			(stroke
				(width 0.1)
				(type default)
			)
			(layer "F.Fab")
		)
		(fp_line
			(start 0.120396 0.3048)
			(end 0.120396 0.2794)
			(stroke
				(width 0.1)
				(type default)
			)
			(layer "F.Fab")
		)
		(fp_line
			(start -0.12065 0.3048)
			(end -0.67945 0.3048)
			(stroke
				(width 0.1)
				(type default)
			)
			(layer "F.Fab")
		)
		(fp_line
			(start -0.67945 0.3048)
			(end -0.67945 -0.305054)
			(stroke
				(width 0.1)
				(type default)
			)
			(layer "F.Fab")
		)
		(pad "1" smd circle
			(at -0.40005 0 90)
			(size 0 0)
			(layers "F.Cu" "F.Mask" "F.Paste")
			(net "PVDD18_S5_P0")
		)
		(pad "2" smd circle
			(at 0.40005 0 90)
			(size 0 0)
			(layers "F.Cu" "F.Mask" "F.Paste")
			(net "GND")
		)
	)
	(footprint ""
		(layer "F.Cu")
		(at 52.705 -433.578)
		(property "Reference" "R3391"
			(at 0 0 0)
			(layer "F.SilkS")
			(hide yes)
			(effects
				(font
					(size 1.27 1.27)
				)
			)
		)
		(property "Value" ""
			(at 0 0 0)
			(layer "F.Fab")
			(effects
				(font
					(size 1.27 1.27)
				)
			)
		)
		(duplicate_pad_numbers_are_jumpers no)
		(fp_line
			(start -0.7874 -0.4064)
			(end 0.7874 -0.4064)
			(stroke
				(width 0.1524)
				(type default)
			)
			(layer "F.SilkS")
		)
		(fp_line
			(start -0.7874 0.4064)
			(end -0.7874 -0.4064)
			(stroke
				(width 0.1524)
				(type default)
			)
			(layer "F.SilkS")
		)
		(fp_line
			(start 0.7874 -0.4064)
			(end 0.7874 0.4064)
			(stroke
				(width 0.1524)
				(type default)
			)
			(layer "F.SilkS")
		)
		(fp_line
			(start 0.7874 0.4064)
			(end -0.7874 0.4064)
			(stroke
				(width 0.1524)
				(type default)
			)
			(layer "F.SilkS")
		)
		(fp_line
			(start -0.67945 -0.305054)
			(end -0.12065 -0.305054)
			(stroke
				(width 0.1)
				(type default)
			)
			(layer "F.Fab")
		)
		(fp_line
			(start -0.67945 0.3048)
			(end -0.67945 -0.305054)
			(stroke
				(width 0.1)
				(type default)
			)
			(layer "F.Fab")
		)
		(fp_line
			(start -0.12065 -0.305054)
			(end -0.12065 -0.2794)
			(stroke
				(width 0.1)
				(type default)
			)
			(layer "F.Fab")
		)
		(fp_line
			(start -0.12065 -0.2794)
			(end 0.12065 -0.2794)
			(stroke
				(width 0.1)
				(type default)
			)
			(layer "F.Fab")
		)
		(fp_line
			(start -0.12065 0.2794)
			(end -0.12065 0.3048)
			(stroke
				(width 0.1)
				(type default)
			)
			(layer "F.Fab")
		)
		(fp_line
			(start -0.12065 0.3048)
			(end -0.67945 0.3048)
			(stroke
				(width 0.1)
				(type default)
			)
			(layer "F.Fab")
		)
		(fp_line
			(start 0.120396 0.2794)
			(end -0.12065 0.2794)
			(stroke
				(width 0.1)
				(type default)
			)
			(layer "F.Fab")
		)
		(fp_line
			(start 0.120396 0.3048)
			(end 0.120396 0.2794)
			(stroke
				(width 0.1)
				(type default)
			)
			(layer "F.Fab")
		)
		(fp_line
			(start 0.12065 -0.3048)
			(end 0.67945 -0.3048)
			(stroke
				(width 0.1)
				(type default)
			)
			(layer "F.Fab")
		)
		(fp_line
			(start 0.12065 -0.2794)
			(end 0.12065 -0.3048)
			(stroke
				(width 0.1)
				(type default)
			)
			(layer "F.Fab")
		)
		(fp_line
			(start 0.67945 -0.3048)
			(end 0.67945 0.3048)
			(stroke
				(width 0.1)
				(type default)
			)
			(layer "F.Fab")
		)
		(fp_line
			(start 0.67945 0.3048)
			(end 0.120396 0.3048)
			(stroke
				(width 0.1)
				(type default)
			)
			(layer "F.Fab")
		)
		(pad "1" smd circle
			(at -0.40005 0)
			(size 0 0)
			(layers "F.Cu" "F.Mask" "F.Paste")
			(net "RST_PERST_2_SWB_BUF_R_N")
		)
		(pad "2" smd circle
			(at 0.40005 0)
			(size 0 0)
			(layers "F.Cu" "F.Mask" "F.Paste")
			(net "RST_PERST_2_SWB_BUF_N")
		)
	)
	(footprint ""
		(layer "F.Cu")
		(at 425.36872 -385.364228)
		(property "Reference" "C840"
			(at 0 0 0)
			(layer "F.SilkS")
			(hide yes)
			(effects
				(font
					(size 1.27 1.27)
				)
			)
		)
		(property "Value" ""
			(at 0 0 0)
			(layer "F.Fab")
			(effects
				(font
					(size 1.27 1.27)
				)
			)
		)
		(duplicate_pad_numbers_are_jumpers no)
		(fp_line
			(start -0.299974 -0.150114)
			(end 0.299974 -0.150114)
			(stroke
				(width 0.1)
				(type default)
			)
			(layer "F.Fab")
		)
		(fp_line
			(start -0.299974 0.150114)
			(end -0.299974 -0.150114)
			(stroke
				(width 0.1)
				(type default)
			)
			(layer "F.Fab")
		)
		(fp_line
			(start 0.299974 -0.150114)
			(end 0.299974 0.150114)
			(stroke
				(width 0.1)
				(type default)
			)
			(layer "F.Fab")
		)
		(fp_line
			(start 0.299974 0.150114)
			(end -0.299974 0.150114)
			(stroke
				(width 0.1)
				(type default)
			)
			(layer "F.Fab")
		)
		(pad "1" smd rect
			(at -0.2667 0)
			(size 0.3048 0.381)
			(layers "F.Cu" "F.Mask" "F.Paste")
			(net "P5E_CPU0_P2_TX_C_DN<14>")
		)
		(pad "2" smd rect
			(at 0.2667 0)
			(size 0.3048 0.381)
			(layers "F.Cu" "F.Mask" "F.Paste")
			(net "P5E_CPU0_P2_TX_DN<14>")
		)
	)
	(footprint ""
		(layer "F.Cu")
		(at 514.718808 -298.391326 90)
		(property "Reference" "X8"
			(at -1.99009 1.316736 0)
			(unlocked yes)
			(layer "F.SilkS")
			(effects
				(font
					(size 0.7874 0.5842)
					(thickness 0.1524)
				)
				(justify left)
			)
		)
		(property "Value" ""
			(at 0 0 90)
			(layer "F.Fab")
			(effects
				(font
					(size 1.27 1.27)
				)
			)
		)
		(property "User Part Number" "N_A"
			(at 1.30175 1.27 180)
			(unlocked yes)
			(layer "Cmts.User")
			(hide yes)
			(effects
				(font
					(size 0.635 0.4064)
					(thickness 0.1524)
				)
			)
		)
		(property "Device Type" "TP_TDR_4P_FTS_TH-TP_TDR_4P_DIP,EMPTY,TP15"
			(at 1.30175 1.27 180)
			(unlocked yes)
			(layer "F.Fab")
			(hide yes)
			(effects
				(font
					(size 0.635 0.4064)
					(thickness 0.1524)
				)
			)
		)
		(duplicate_pad_numbers_are_jumpers no)
		(fp_line
			(start 2.54 -1.27)
			(end 0 -1.27)
			(stroke
				(width 0.1524)
				(type default)
			)
			(layer "F.SilkS")
		)
		(fp_line
			(start 0 -1.27)
			(end 0 -0.635)
			(stroke
				(width 0.1524)
				(type default)
			)
			(layer "F.SilkS")
		)
		(fp_line
			(start 2.54 -1.1303)
			(end 2.54 -1.27)
			(stroke
				(width 0.1524)
				(type default)
			)
			(layer "F.SilkS")
		)
		(fp_line
			(start 0 0.635)
			(end 0 1.905)
			(stroke
				(width 0.1524)
				(type default)
			)
			(layer "F.SilkS")
		)
		(fp_line
			(start 2.54 1.4097)
			(end 2.54 1.1303)
			(stroke
				(width 0.1524)
				(type default)
			)
			(layer "F.SilkS")
		)
		(fp_line
			(start 0 3.175)
			(end 0 3.81)
			(stroke
				(width 0.1524)
				(type default)
			)
			(layer "F.SilkS")
		)
		(fp_line
			(start 2.54 3.81)
			(end 2.54 3.6703)
			(stroke
				(width 0.1524)
				(type default)
			)
			(layer "F.SilkS")
		)
		(fp_line
			(start 0 3.81)
			(end 2.54 3.81)
			(stroke
				(width 0.1524)
				(type default)
			)
			(layer "F.SilkS")
		)
		(fp_poly
			(pts
				(xy -0.761746 0) (xy -2.285746 0.762) (xy -2.285746 -0.762)
			)
			(stroke
				(width 0)
				(type default)
			)
			(fill yes)
			(layer "F.SilkS")
		)
		(fp_line
			(start 2.54 -1.27)
			(end 0 -1.27)
			(stroke
				(width 0.1)
				(type default)
			)
			(layer "F.Fab")
		)
		(fp_line
			(start 0 -1.27)
			(end 0 3.81)
			(stroke
				(width 0.1)
				(type default)
			)
			(layer "F.Fab")
		)
		(fp_line
			(start 2.54 3.81)
			(end 2.54 -1.27)
			(stroke
				(width 0.1)
				(type default)
			)
			(layer "F.Fab")
		)
		(fp_line
			(start 0 3.81)
			(end 2.54 3.81)
			(stroke
				(width 0.1)
				(type default)
			)
			(layer "F.Fab")
		)
		(fp_poly
			(pts
				(xy -0.761746 0) (xy -2.285746 -0.762) (xy -2.285746 0.762)
			)
			(stroke
				(width 0)
				(type default)
			)
			(fill yes)
			(layer "F.Fab")
		)
		(pad "1" thru_hole circle
			(at 0 0 90)
			(size 1.0033 1.0033)
			(drill 0.249936)
			(layers "*.Cu" "*.Mask")
			(remove_unused_layers no)
			(net "TDR_DIFF_80_IN1_DN")
			(clearance 0.10795)
			(thermal_gap 0.10795)
			(padstack
				(mode front_inner_back)
				(layer "Inner"
					(shape circle)
					(size 0.8001 0.8001)
					(clearance 0.1524)
				)
				(layer "B.Cu"
					(shape circle)
					(size 1.0033 1.0033)
					(clearance 0.10795)
				)
			)
		)
		(pad "2" thru_hole circle
			(at 2.54 0 90)
			(size 1.9939 1.9939)
			(drill 0.249936)
			(layers "*.Cu" "*.Mask")
			(remove_unused_layers no)
			(net "T1_GND")
			(clearance 0.10795)
			(thermal_gap 0.10795)
			(padstack
				(mode front_inner_back)
				(layer "Inner"
					(shape circle)
					(size 0.8001 0.8001)
					(clearance 0.1524)
				)
				(layer "B.Cu"
					(shape circle)
					(size 1.9939 1.9939)
					(clearance 0.10795)
				)
			)
		)
		(pad "3" thru_hole circle
			(at 2.54 2.54 90)
			(size 1.9939 1.9939)
			(drill 0.249936)
			(layers "*.Cu" "*.Mask")
			(remove_unused_layers no)
			(net "T1_GND")
			(clearance 0.10795)
			(thermal_gap 0.10795)
			(padstack
				(mode front_inner_back)
				(layer "Inner"
					(shape circle)
					(size 0.8001 0.8001)
					(clearance 0.1524)
				)
				(layer "B.Cu"
					(shape circle)
					(size 1.9939 1.9939)
					(clearance 0.10795)
				)
			)
		)
		(pad "4" thru_hole circle
			(at 0 2.54 90)
			(size 1.0033 1.0033)
			(drill 0.249936)
			(layers "*.Cu" "*.Mask")
			(remove_unused_layers no)
			(net "TDR_DIFF_80_IN1_DP")
			(clearance 0.10795)
			(thermal_gap 0.10795)
			(padstack
				(mode front_inner_back)
				(layer "Inner"
					(shape circle)
					(size 0.8001 0.8001)
					(clearance 0.1524)
				)
				(layer "B.Cu"
					(shape circle)
					(size 1.0033 1.0033)
					(clearance 0.10795)
				)
			)
		)
	)
	(footprint ""
		(layer "F.Cu")
		(at 120.68175 -25.545796)
		(property "Reference" "R6264"
			(at 0 0 0)
			(layer "F.SilkS")
			(hide yes)
			(effects
				(font
					(size 1.27 1.27)
				)
			)
		)
		(property "Value" ""
			(at 0 0 0)
			(layer "F.Fab")
			(effects
				(font
					(size 1.27 1.27)
				)
			)
		)
		(duplicate_pad_numbers_are_jumpers no)
		(fp_line
			(start -0.7874 -0.4064)
			(end 0.7874 -0.4064)
			(stroke
				(width 0.1524)
				(type default)
			)
			(layer "F.SilkS")
		)
		(fp_line
			(start -0.7874 0.4064)
			(end -0.7874 -0.4064)
			(stroke
				(width 0.1524)
				(type default)
			)
			(layer "F.SilkS")
		)
		(fp_line
			(start 0.7874 -0.4064)
			(end 0.7874 0.4064)
			(stroke
				(width 0.1524)
				(type default)
			)
			(layer "F.SilkS")
		)
		(fp_line
			(start 0.7874 0.4064)
			(end -0.7874 0.4064)
			(stroke
				(width 0.1524)
				(type default)
			)
			(layer "F.SilkS")
		)
		(fp_line
			(start -0.67945 -0.305054)
			(end -0.12065 -0.305054)
			(stroke
				(width 0.1)
				(type default)
			)
			(layer "F.Fab")
		)
		(fp_line
			(start -0.67945 0.3048)
			(end -0.67945 -0.305054)
			(stroke
				(width 0.1)
				(type default)
			)
			(layer "F.Fab")
		)
		(fp_line
			(start -0.12065 -0.305054)
			(end -0.12065 -0.2794)
			(stroke
				(width 0.1)
				(type default)
			)
			(layer "F.Fab")
		)
		(fp_line
			(start -0.12065 -0.2794)
			(end 0.12065 -0.2794)
			(stroke
				(width 0.1)
				(type default)
			)
			(layer "F.Fab")
		)
		(fp_line
			(start -0.12065 0.2794)
			(end -0.12065 0.3048)
			(stroke
				(width 0.1)
				(type default)
			)
			(layer "F.Fab")
		)
		(fp_line
			(start -0.12065 0.3048)
			(end -0.67945 0.3048)
			(stroke
				(width 0.1)
				(type default)
			)
			(layer "F.Fab")
		)
		(fp_line
			(start 0.120396 0.2794)
			(end -0.12065 0.2794)
			(stroke
				(width 0.1)
				(type default)
			)
			(layer "F.Fab")
		)
		(fp_line
			(start 0.120396 0.3048)
			(end 0.120396 0.2794)
			(stroke
				(width 0.1)
				(type default)
			)
			(layer "F.Fab")
		)
		(fp_line
			(start 0.12065 -0.3048)
			(end 0.67945 -0.3048)
			(stroke
				(width 0.1)
				(type default)
			)
			(layer "F.Fab")
		)
		(fp_line
			(start 0.12065 -0.2794)
			(end 0.12065 -0.3048)
			(stroke
				(width 0.1)
				(type default)
			)
			(layer "F.Fab")
		)
		(fp_line
			(start 0.67945 -0.3048)
			(end 0.67945 0.3048)
			(stroke
				(width 0.1)
				(type default)
			)
			(layer "F.Fab")
		)
		(fp_line
			(start 0.67945 0.3048)
			(end 0.120396 0.3048)
			(stroke
				(width 0.1)
				(type default)
			)
			(layer "F.Fab")
		)
		(pad "1" smd circle
			(at -0.40005 0)
			(size 0 0)
			(layers "F.Cu" "F.Mask" "F.Paste")
			(net "USB_HUB2_TI_USB_DM_DN3_MRP_VDD33")
		)
		(pad "2" smd circle
			(at 0.40005 0)
			(size 0 0)
			(layers "F.Cu" "F.Mask" "F.Paste")
			(net "P3V3_AUX_CPU0_USB2_AVDD33")
		)
	)
)
